(kicad_pcb
	(version 20260206)
	(generator "pcbnew")
	(generator_version "10.0")
	(general
		(thickness 1.6)
		(legacy_teardrops no)
	)
	(paper "A4")
	(title_block
		(title "04192023_DAF0TMB3IC0_F0TG_MB_C_brd_V02_OCP.brd")
		(comment 1 "Grand Teton / footprints 5217-5223 of 8354")
	)
	(layers
		(0 "F.Cu" signal "TOP")
		(4 "In1.Cu" signal "GND")
		(6 "In2.Cu" signal "IN1")
		(8 "In3.Cu" signal "GND1")
		(10 "In4.Cu" signal "IN2")
		(12 "In5.Cu" signal "GND2")
		(14 "In6.Cu" signal "IN3")
		(16 "In7.Cu" signal "GND3")
		(18 "In8.Cu" signal "VCC")
		(20 "In9.Cu" signal "VCC1")
		(22 "In10.Cu" signal "GND4")
		(24 "In11.Cu" signal "IN4")
		(26 "In12.Cu" signal "GND5")
		(28 "In13.Cu" signal "IN5")
		(30 "In14.Cu" signal "GND6")
		(32 "In15.Cu" signal "IN6")
		(34 "In16.Cu" signal "GND7")
		(2 "B.Cu" signal "BOTTOM")
		(9 "F.Adhes" user "F.Adhesive")
		(11 "B.Adhes" user "B.Adhesive")
		(13 "F.Paste" user "Package Geometry/Pastemask Top")
		(15 "B.Paste" user "Package Geometry/Pastemask Bottom")
		(5 "F.SilkS" user "Ref Des/Silkscreen Top")
		(7 "B.SilkS" user "Ref Des/Silkscreen Bottom")
		(1 "F.Mask" user "Board Geometry/Soldermask Top")
		(3 "B.Mask" user "Board Geometry/Soldermask Bottom")
		(17 "Dwgs.User" user "User.Drawings")
		(19 "Cmts.User" user "User.Comments")
		(21 "Eco1.User" user "User.Eco1")
		(23 "Eco2.User" user "User.Eco2")
		(25 "Edge.Cuts" user "Board Geometry/Outline")
		(27 "Margin" user)
		(31 "F.CrtYd" user "Package Geometry/Place Bound Top")
		(29 "B.CrtYd" user "Package Geometry/Place Bound Bottom")
		(35 "F.Fab" user "Ref Des/Assembly Top")
		(33 "B.Fab" user "Ref Des/Assembly Bottom")
	)
	(footprint ""
		(layer "B.Cu")
		(at 256.432558 -328.744072)
		(property "Reference" "R1230"
			(at 0 0 0)
			(layer "B.SilkS")
			(hide yes)
			(effects
				(font
					(size 1.27 1.27)
				)
				(justify mirror)
			)
		)
		(property "Value" ""
			(at 0 0 0)
			(layer "B.Fab")
			(effects
				(font
					(size 1.27 1.27)
				)
				(justify mirror)
			)
		)
		(duplicate_pad_numbers_are_jumpers no)
		(fp_line
			(start -0.7874 -0.4064)
			(end -0.7874 0.4064)
			(stroke
				(width 0.1524)
				(type default)
			)
			(layer "B.SilkS")
		)
		(fp_line
			(start -0.7874 0.4064)
			(end 0.7874 0.4064)
			(stroke
				(width 0.1524)
				(type default)
			)
			(layer "B.SilkS")
		)
		(fp_line
			(start 0.7874 -0.4064)
			(end -0.7874 -0.4064)
			(stroke
				(width 0.1524)
				(type default)
			)
			(layer "B.SilkS")
		)
		(fp_line
			(start 0.7874 0.4064)
			(end 0.7874 -0.4064)
			(stroke
				(width 0.1524)
				(type default)
			)
			(layer "B.SilkS")
		)
		(fp_line
			(start -0.67945 -0.3048)
			(end -0.67945 0.3048)
			(stroke
				(width 0.1)
				(type default)
			)
			(layer "B.Fab")
		)
		(fp_line
			(start -0.67945 0.3048)
			(end -0.120396 0.3048)
			(stroke
				(width 0.1)
				(type default)
			)
			(layer "B.Fab")
		)
		(fp_line
			(start -0.12065 -0.3048)
			(end -0.67945 -0.3048)
			(stroke
				(width 0.1)
				(type default)
			)
			(layer "B.Fab")
		)
		(fp_line
			(start -0.12065 -0.2794)
			(end -0.12065 -0.3048)
			(stroke
				(width 0.1)
				(type default)
			)
			(layer "B.Fab")
		)
		(fp_line
			(start -0.120396 0.2794)
			(end 0.12065 0.2794)
			(stroke
				(width 0.1)
				(type default)
			)
			(layer "B.Fab")
		)
		(fp_line
			(start -0.120396 0.3048)
			(end -0.120396 0.2794)
			(stroke
				(width 0.1)
				(type default)
			)
			(layer "B.Fab")
		)
		(fp_line
			(start 0.12065 -0.305054)
			(end 0.12065 -0.2794)
			(stroke
				(width 0.1)
				(type default)
			)
			(layer "B.Fab")
		)
		(fp_line
			(start 0.12065 -0.2794)
			(end -0.12065 -0.2794)
			(stroke
				(width 0.1)
				(type default)
			)
			(layer "B.Fab")
		)
		(fp_line
			(start 0.12065 0.2794)
			(end 0.12065 0.3048)
			(stroke
				(width 0.1)
				(type default)
			)
			(layer "B.Fab")
		)
		(fp_line
			(start 0.12065 0.3048)
			(end 0.67945 0.3048)
			(stroke
				(width 0.1)
				(type default)
			)
			(layer "B.Fab")
		)
		(fp_line
			(start 0.67945 -0.305054)
			(end 0.12065 -0.305054)
			(stroke
				(width 0.1)
				(type default)
			)
			(layer "B.Fab")
		)
		(fp_line
			(start 0.67945 0.3048)
			(end 0.67945 -0.305054)
			(stroke
				(width 0.1)
				(type default)
			)
			(layer "B.Fab")
		)
		(pad "1" smd circle
			(at 0.40005 0 180)
			(size 0 0)
			(layers "B.Cu" "B.Mask" "B.Paste")
			(net "MAX11617_2_VREF")
		)
		(pad "2" smd circle
			(at -0.40005 0 180)
			(size 0 0)
			(layers "B.Cu" "B.Mask" "B.Paste")
			(net "MAX11617_2_VREF_R")
		)
	)
	(footprint ""
		(layer "B.Cu")
		(at 231.834182 -328.25182 180)
		(property "Reference" "R1247"
			(at 0 0 0)
			(layer "B.SilkS")
			(hide yes)
			(effects
				(font
					(size 1.27 1.27)
				)
				(justify mirror)
			)
		)
		(property "Value" ""
			(at 0 0 0)
			(layer "B.Fab")
			(effects
				(font
					(size 1.27 1.27)
				)
				(justify mirror)
			)
		)
		(duplicate_pad_numbers_are_jumpers no)
		(fp_line
			(start 0.7874 0.4064)
			(end 0.7874 -0.4064)
			(stroke
				(width 0.1524)
				(type default)
			)
			(layer "B.SilkS")
		)
		(fp_line
			(start 0.7874 -0.4064)
			(end -0.7874 -0.4064)
			(stroke
				(width 0.1524)
				(type default)
			)
			(layer "B.SilkS")
		)
		(fp_line
			(start -0.7874 0.4064)
			(end 0.7874 0.4064)
			(stroke
				(width 0.1524)
				(type default)
			)
			(layer "B.SilkS")
		)
		(fp_line
			(start -0.7874 -0.4064)
			(end -0.7874 0.4064)
			(stroke
				(width 0.1524)
				(type default)
			)
			(layer "B.SilkS")
		)
		(fp_line
			(start 0.67945 0.3048)
			(end 0.67945 -0.305054)
			(stroke
				(width 0.1)
				(type default)
			)
			(layer "B.Fab")
		)
		(fp_line
			(start 0.67945 -0.305054)
			(end 0.12065 -0.305054)
			(stroke
				(width 0.1)
				(type default)
			)
			(layer "B.Fab")
		)
		(fp_line
			(start 0.12065 0.3048)
			(end 0.67945 0.3048)
			(stroke
				(width 0.1)
				(type default)
			)
			(layer "B.Fab")
		)
		(fp_line
			(start 0.12065 0.2794)
			(end 0.12065 0.3048)
			(stroke
				(width 0.1)
				(type default)
			)
			(layer "B.Fab")
		)
		(fp_line
			(start 0.12065 -0.2794)
			(end -0.12065 -0.2794)
			(stroke
				(width 0.1)
				(type default)
			)
			(layer "B.Fab")
		)
		(fp_line
			(start 0.12065 -0.305054)
			(end 0.12065 -0.2794)
			(stroke
				(width 0.1)
				(type default)
			)
			(layer "B.Fab")
		)
		(fp_line
			(start -0.120396 0.3048)
			(end -0.120396 0.2794)
			(stroke
				(width 0.1)
				(type default)
			)
			(layer "B.Fab")
		)
		(fp_line
			(start -0.120396 0.2794)
			(end 0.12065 0.2794)
			(stroke
				(width 0.1)
				(type default)
			)
			(layer "B.Fab")
		)
		(fp_line
			(start -0.12065 -0.2794)
			(end -0.12065 -0.3048)
			(stroke
				(width 0.1)
				(type default)
			)
			(layer "B.Fab")
		)
		(fp_line
			(start -0.12065 -0.3048)
			(end -0.67945 -0.3048)
			(stroke
				(width 0.1)
				(type default)
			)
			(layer "B.Fab")
		)
		(fp_line
			(start -0.67945 0.3048)
			(end -0.120396 0.3048)
			(stroke
				(width 0.1)
				(type default)
			)
			(layer "B.Fab")
		)
		(fp_line
			(start -0.67945 -0.3048)
			(end -0.67945 0.3048)
			(stroke
				(width 0.1)
				(type default)
			)
			(layer "B.Fab")
		)
		(pad "1" smd rect
			(at 0.40005 0 180)
			(size 0.4572 0.508)
			(layers "B.Cu" "B.Mask" "B.Paste")
			(net "PVDD18_S5_P0_ADC")
		)
		(pad "2" smd rect
			(at -0.40005 0 180)
			(size 0.4572 0.508)
			(layers "B.Cu" "B.Mask" "B.Paste")
			(net "PVDD18_S5_P0_ADC_MAM")
		)
	)
	(footprint ""
		(layer "B.Cu")
		(at 217.678 -334.01 180)
		(property "Reference" "R6810"
			(at 0 0 0)
			(layer "B.SilkS")
			(hide yes)
			(effects
				(font
					(size 1.27 1.27)
				)
				(justify mirror)
			)
		)
		(property "Value" ""
			(at 0 0 0)
			(layer "B.Fab")
			(effects
				(font
					(size 1.27 1.27)
				)
				(justify mirror)
			)
		)
		(duplicate_pad_numbers_are_jumpers no)
		(fp_line
			(start 0.32512 0.175006)
			(end 0.32512 -0.175006)
			(stroke
				(width 0.1)
				(type default)
			)
			(layer "B.Fab")
		)
		(fp_line
			(start 0.32512 -0.175006)
			(end -0.32512 -0.175006)
			(stroke
				(width 0.1)
				(type default)
			)
			(layer "B.Fab")
		)
		(fp_line
			(start -0.32512 0.175006)
			(end 0.32512 0.175006)
			(stroke
				(width 0.1)
				(type default)
			)
			(layer "B.Fab")
		)
		(fp_line
			(start -0.32512 -0.175006)
			(end -0.32512 0.175006)
			(stroke
				(width 0.1)
				(type default)
			)
			(layer "B.Fab")
		)
		(pad "1" smd rect
			(at 0.2667 0)
			(size 0.3048 0.381)
			(layers "B.Cu" "B.Mask" "B.Paste")
			(net "SMB_RT_CPU1_P0_R_SDA")
		)
		(pad "2" smd rect
			(at -0.2667 0 180)
			(size 0.3048 0.381)
			(layers "B.Cu" "B.Mask" "B.Paste")
			(net "SMB_RT_CPU1_P0_SDA")
		)
	)
	(footprint ""
		(layer "B.Cu")
		(at 30.65526 -353.11334)
		(property "Reference" "PC7001"
			(at 0 0 0)
			(layer "B.SilkS")
			(hide yes)
			(effects
				(font
					(size 1.27 1.27)
				)
				(justify mirror)
			)
		)
		(property "Value" ""
			(at 0 0 0)
			(layer "B.Fab")
			(effects
				(font
					(size 1.27 1.27)
				)
				(justify mirror)
			)
		)
		(duplicate_pad_numbers_are_jumpers no)
		(fp_line
			(start -1.524 -0.762)
			(end -1.524 0.762)
			(stroke
				(width 0.1524)
				(type default)
			)
			(layer "B.SilkS")
		)
		(fp_line
			(start -1.524 0.762)
			(end 1.524 0.762)
			(stroke
				(width 0.1524)
				(type default)
			)
			(layer "B.SilkS")
		)
		(fp_line
			(start 1.524 -0.762)
			(end -1.524 -0.762)
			(stroke
				(width 0.1524)
				(type default)
			)
			(layer "B.SilkS")
		)
		(fp_line
			(start 1.524 0.762)
			(end 1.524 -0.762)
			(stroke
				(width 0.1524)
				(type default)
			)
			(layer "B.SilkS")
		)
		(fp_line
			(start -1.1049 -0.724916)
			(end 1.1049 -0.724916)
			(stroke
				(width 0.1)
				(type default)
			)
			(layer "B.Fab")
		)
		(fp_line
			(start -1.1049 0.724916)
			(end -1.1049 -0.724916)
			(stroke
				(width 0.1)
				(type default)
			)
			(layer "B.Fab")
		)
		(fp_line
			(start 1.1049 -0.724916)
			(end 1.1049 0.724916)
			(stroke
				(width 0.1)
				(type default)
			)
			(layer "B.Fab")
		)
		(fp_line
			(start 1.1049 0.724916)
			(end -1.1049 0.724916)
			(stroke
				(width 0.1)
				(type default)
			)
			(layer "B.Fab")
		)
		(pad "1" smd rect
			(at 0.889 0)
			(size 1.016 1.27)
			(layers "B.Cu" "B.Mask" "B.Paste")
			(net "SW_P12V_AUX_PVDDIO_P1_FLT")
		)
		(pad "2" smd rect
			(at -0.889 0)
			(size 1.016 1.27)
			(layers "B.Cu" "B.Mask" "B.Paste")
			(net "GND")
		)
	)
	(footprint ""
		(layer "B.Cu")
		(at 449.932552 -380.027434 90)
		(property "Reference" "PC6570"
			(at -6.293104 2.314448 0)
			(unlocked yes)
			(layer "B.SilkS")
			(effects
				(font
					(size 0.7874 0.5842)
					(thickness 0.1524)
				)
				(justify left mirror)
			)
		)
		(property "Value" ""
			(at 0 0 90)
			(layer "B.Fab")
			(effects
				(font
					(size 1.27 1.27)
				)
				(justify mirror)
			)
		)
		(duplicate_pad_numbers_are_jumpers no)
		(fp_line
			(start 4.84378 -2.150618)
			(end 4.53898 -2.150618)
			(stroke
				(width 0.1524)
				(type default)
			)
			(layer "B.SilkS")
		)
		(fp_line
			(start 4.84378 -2.150618)
			(end 4.842256 2.163064)
			(stroke
				(width 0.1524)
				(type default)
			)
			(layer "B.SilkS")
		)
		(fp_line
			(start 4.69138 -2.150618)
			(end 4.692396 2.161032)
			(stroke
				(width 0.1524)
				(type default)
			)
			(layer "B.SilkS")
		)
		(fp_line
			(start 4.53898 -2.150618)
			(end 4.539742 2.152142)
			(stroke
				(width 0.1524)
				(type default)
			)
			(layer "B.SilkS")
		)
		(fp_line
			(start 4.53898 -2.15011)
			(end -4.53898 -2.15011)
			(stroke
				(width 0.1524)
				(type default)
			)
			(layer "B.SilkS")
		)
		(fp_line
			(start -4.53898 -2.15011)
			(end -4.53898 2.15011)
			(stroke
				(width 0.1524)
				(type default)
			)
			(layer "B.SilkS")
		)
		(fp_line
			(start 4.53898 2.15011)
			(end 4.53898 -2.15011)
			(stroke
				(width 0.1524)
				(type default)
			)
			(layer "B.SilkS")
		)
		(fp_line
			(start -4.53898 2.15011)
			(end 4.53898 2.15011)
			(stroke
				(width 0.1524)
				(type default)
			)
			(layer "B.SilkS")
		)
		(fp_line
			(start 4.83108 2.150364)
			(end 4.447794 2.149348)
			(stroke
				(width 0.1524)
				(type default)
			)
			(layer "B.SilkS")
		)
		(fp_line
			(start 3.64998 -2.15011)
			(end -3.64998 -2.15011)
			(stroke
				(width 0.1)
				(type default)
			)
			(layer "B.Fab")
		)
		(fp_line
			(start -3.64998 -2.15011)
			(end -3.64998 2.15011)
			(stroke
				(width 0.1)
				(type default)
			)
			(layer "B.Fab")
		)
		(fp_line
			(start 3.64998 2.15011)
			(end 3.64998 -2.15011)
			(stroke
				(width 0.1)
				(type default)
			)
			(layer "B.Fab")
		)
		(fp_line
			(start -3.64998 2.15011)
			(end 3.64998 2.15011)
			(stroke
				(width 0.1)
				(type default)
			)
			(layer "B.Fab")
		)
		(fp_text user "-"
			(at -4.313174 -0.094488 90)
			(unlocked yes)
			(layer "B.SilkS")
			(effects
				(font
					(size 1.905 1.4224)
					(thickness 0.1524)
				)
				(justify left mirror)
			)
		)
		(fp_text user "+"
			(at 6.179566 0.060198 90)
			(unlocked yes)
			(layer "B.SilkS")
			(effects
				(font
					(size 1.905 1.4224)
					(thickness 0.1524)
				)
				(justify left mirror)
			)
		)
		(fp_text user "+"
			(at 6.214872 -0.337058 90)
			(unlocked yes)
			(layer "B.Fab")
			(effects
				(font
					(size 1.905 1.4224)
					(thickness 0.1524)
				)
				(justify left mirror)
			)
		)
		(fp_text user "-"
			(at -4.313174 -0.094488 90)
			(unlocked yes)
			(layer "B.Fab")
			(effects
				(font
					(size 1.905 1.4224)
					(thickness 0.1524)
				)
				(justify left mirror)
			)
		)
		(pad "1" smd rect
			(at 3.199892 0 270)
			(size 2.413 2.8194)
			(layers "B.Cu" "B.Mask" "B.Paste")
			(net "P0V9_CPU0_RT_2D")
		)
		(pad "2" smd rect
			(at -3.199892 0 270)
			(size 2.413 2.8194)
			(layers "B.Cu" "B.Mask" "B.Paste")
			(net "GND")
		)
	)
	(footprint ""
		(layer "B.Cu")
		(at 106.98861 -393.242546 180)
		(property "Reference" "R898"
			(at 0 0 0)
			(layer "B.SilkS")
			(hide yes)
			(effects
				(font
					(size 1.27 1.27)
				)
				(justify mirror)
			)
		)
		(property "Value" ""
			(at 0 0 0)
			(layer "B.Fab")
			(effects
				(font
					(size 1.27 1.27)
				)
				(justify mirror)
			)
		)
		(duplicate_pad_numbers_are_jumpers no)
		(fp_line
			(start 1.2954 0.5842)
			(end 1.2954 -0.5842)
			(stroke
				(width 0.1524)
				(type default)
			)
			(layer "B.SilkS")
		)
		(fp_line
			(start 1.2954 -0.5842)
			(end -1.2954 -0.5842)
			(stroke
				(width 0.1524)
				(type default)
			)
			(layer "B.SilkS")
		)
		(fp_line
			(start -1.2954 0.5842)
			(end 1.2954 0.5842)
			(stroke
				(width 0.1524)
				(type default)
			)
			(layer "B.SilkS")
		)
		(fp_line
			(start -1.2954 -0.5842)
			(end -1.2954 0.5842)
			(stroke
				(width 0.1524)
				(type default)
			)
			(layer "B.SilkS")
		)
		(fp_line
			(start 1.1938 0.4064)
			(end 1.1938 -0.406654)
			(stroke
				(width 0.1)
				(type default)
			)
			(layer "B.Fab")
		)
		(fp_line
			(start 1.1938 -0.406654)
			(end 0.8636 -0.406654)
			(stroke
				(width 0.1)
				(type default)
			)
			(layer "B.Fab")
		)
		(fp_line
			(start 0.8636 0.4572)
			(end 0.8636 0.4318)
			(stroke
				(width 0.1)
				(type default)
			)
			(layer "B.Fab")
		)
		(fp_line
			(start 0.8636 0.4318)
			(end 0.8636 0.4064)
			(stroke
				(width 0.1)
				(type default)
			)
			(layer "B.Fab")
		)
		(fp_line
			(start 0.8636 0.4064)
			(end 1.1938 0.4064)
			(stroke
				(width 0.1)
				(type default)
			)
			(layer "B.Fab")
		)
		(fp_line
			(start 0.8636 -0.406654)
			(end 0.8636 -0.4572)
			(stroke
				(width 0.1)
				(type default)
			)
			(layer "B.Fab")
		)
		(fp_line
			(start 0.8636 -0.4572)
			(end -0.8636 -0.4572)
			(stroke
				(width 0.1)
				(type default)
			)
			(layer "B.Fab")
		)
		(fp_line
			(start -0.8636 0.4572)
			(end 0.8636 0.4572)
			(stroke
				(width 0.1)
				(type default)
			)
			(layer "B.Fab")
		)
		(fp_line
			(start -0.8636 0.4064)
			(end -0.8636 0.4572)
			(stroke
				(width 0.1)
				(type default)
			)
			(layer "B.Fab")
		)
		(fp_line
			(start -0.8636 -0.406654)
			(end -1.1938 -0.406654)
			(stroke
				(width 0.1)
				(type default)
			)
			(layer "B.Fab")
		)
		(fp_line
			(start -0.8636 -0.4572)
			(end -0.8636 -0.406654)
			(stroke
				(width 0.1)
				(type default)
			)
			(layer "B.Fab")
		)
		(fp_line
			(start -1.1938 0.4064)
			(end -0.8636 0.4064)
			(stroke
				(width 0.1)
				(type default)
			)
			(layer "B.Fab")
		)
		(fp_line
			(start -1.1938 -0.406654)
			(end -1.1938 0.4064)
			(stroke
				(width 0.1)
				(type default)
			)
			(layer "B.Fab")
		)
		(pad "1" smd rect
			(at 0.7366 0 90)
			(size 0.7112 0.8128)
			(layers "B.Cu" "B.Mask" "B.Paste")
			(net "P0V9_CPU1_RT_2D")
		)
		(pad "2" smd rect
			(at -0.7366 0 90)
			(size 0.7112 0.8128)
			(layers "B.Cu" "B.Mask" "B.Paste")
			(net "P0V9_CPU1_RT3_2A_2D")
		)
	)
	(footprint ""
		(layer "B.Cu")
		(at 171.201334 -103.942388 180)
		(property "Reference" "R6150"
			(at 0 0 0)
			(layer "B.SilkS")
			(hide yes)
			(effects
				(font
					(size 1.27 1.27)
				)
				(justify mirror)
			)
		)
		(property "Value" ""
			(at 0 0 0)
			(layer "B.Fab")
			(effects
				(font
					(size 1.27 1.27)
				)
				(justify mirror)
			)
		)
		(duplicate_pad_numbers_are_jumpers no)
		(fp_line
			(start 0.7874 0.4064)
			(end 0.7874 -0.4064)
			(stroke
				(width 0.1524)
				(type default)
			)
			(layer "B.SilkS")
		)
		(fp_line
			(start 0.7874 -0.4064)
			(end -0.7874 -0.4064)
			(stroke
				(width 0.1524)
				(type default)
			)
			(layer "B.SilkS")
		)
		(fp_line
			(start -0.7874 0.4064)
			(end 0.7874 0.4064)
			(stroke
				(width 0.1524)
				(type default)
			)
			(layer "B.SilkS")
		)
		(fp_line
			(start -0.7874 -0.4064)
			(end -0.7874 0.4064)
			(stroke
				(width 0.1524)
				(type default)
			)
			(layer "B.SilkS")
		)
		(fp_line
			(start 0.67945 0.3048)
			(end 0.67945 -0.305054)
			(stroke
				(width 0.1)
				(type default)
			)
			(layer "B.Fab")
		)
		(fp_line
			(start 0.67945 -0.305054)
			(end 0.12065 -0.305054)
			(stroke
				(width 0.1)
				(type default)
			)
			(layer "B.Fab")
		)
		(fp_line
			(start 0.12065 0.3048)
			(end 0.67945 0.3048)
			(stroke
				(width 0.1)
				(type default)
			)
			(layer "B.Fab")
		)
		(fp_line
			(start 0.12065 0.2794)
			(end 0.12065 0.3048)
			(stroke
				(width 0.1)
				(type default)
			)
			(layer "B.Fab")
		)
		(fp_line
			(start 0.12065 -0.2794)
			(end -0.12065 -0.2794)
			(stroke
				(width 0.1)
				(type default)
			)
			(layer "B.Fab")
		)
		(fp_line
			(start 0.12065 -0.305054)
			(end 0.12065 -0.2794)
			(stroke
				(width 0.1)
				(type default)
			)
			(layer "B.Fab")
		)
		(fp_line
			(start -0.120396 0.3048)
			(end -0.120396 0.2794)
			(stroke
				(width 0.1)
				(type default)
			)
			(layer "B.Fab")
		)
		(fp_line
			(start -0.120396 0.2794)
			(end 0.12065 0.2794)
			(stroke
				(width 0.1)
				(type default)
			)
			(layer "B.Fab")
		)
		(fp_line
			(start -0.12065 -0.2794)
			(end -0.12065 -0.3048)
			(stroke
				(width 0.1)
				(type default)
			)
			(layer "B.Fab")
		)
		(fp_line
			(start -0.12065 -0.3048)
			(end -0.67945 -0.3048)
			(stroke
				(width 0.1)
				(type default)
			)
			(layer "B.Fab")
		)
		(fp_line
			(start -0.67945 0.3048)
			(end -0.120396 0.3048)
			(stroke
				(width 0.1)
				(type default)
			)
			(layer "B.Fab")
		)
		(fp_line
			(start -0.67945 -0.3048)
			(end -0.67945 0.3048)
			(stroke
				(width 0.1)
				(type default)
			)
			(layer "B.Fab")
		)
		(pad "1" smd circle
			(at 0.40005 0)
			(size 0 0)
			(layers "B.Cu" "B.Mask" "B.Paste")
			(net "FAB_BMC_REV_ID1")
		)
		(pad "2" smd circle
			(at -0.40005 0)
			(size 0 0)
			(layers "B.Cu" "B.Mask" "B.Paste")
			(net "GND")
		)
	)
)
